(kicad_pcb
	(version 20260206)
	(generator "pcbnew")
	(generator_version "10.0")
	(general
		(thickness 1.6)
		(legacy_teardrops no)
	)
	(paper "A4")
	(title_block
		(title "panther-plus-userver — 13130-1b_20150205.brd")
		(comment 1 "Honey Badger (Wiwynn) / footprints 404-405 of 1509")
	)
	(layers
		(0 "F.Cu" signal "TOP")
		(4 "In1.Cu" signal "L2")
		(6 "In2.Cu" signal "L3")
		(8 "In3.Cu" signal "L4")
		(10 "In4.Cu" signal "L5")
		(12 "In5.Cu" signal "L6")
		(14 "In6.Cu" signal "L7")
		(16 "In7.Cu" signal "L8")
		(18 "In8.Cu" signal "L9")
		(20 "In9.Cu" signal "L10")
		(22 "In10.Cu" signal "L11")
		(2 "B.Cu" signal "BOTTOM")
		(9 "F.Adhes" user "F.Adhesive")
		(11 "B.Adhes" user "B.Adhesive")
		(13 "F.Paste" user "Package Geometry/Pastemask Top")
		(15 "B.Paste" user "Package Geometry/Pastemask Bottom")
		(5 "F.SilkS" user "Ref Des/Silkscreen Top")
		(7 "B.SilkS" user "Ref Des/Silkscreen Bottom")
		(1 "F.Mask" user "Board Geometry/Soldermask Top")
		(3 "B.Mask" user "Board Geometry/Soldermask Bottom")
		(17 "Dwgs.User" user "User.Drawings")
		(19 "Cmts.User" user "User.Comments")
		(21 "Eco1.User" user "User.Eco1")
		(23 "Eco2.User" user "User.Eco2")
		(25 "Edge.Cuts" user "Board Geometry/Outline")
		(27 "Margin" user)
		(31 "F.CrtYd" user "Package Geometry/Place Bound Top")
		(29 "B.CrtYd" user "Package Geometry/Place Bound Bottom")
		(35 "F.Fab" user "Ref Des/Assembly Top")
		(33 "B.Fab" user "Ref Des/Assembly Bottom")
	)
	(footprint ""
		(layer "F.Cu")
		(at 167.894 -24.765 -90)
		(property "Reference" "PC98"
			(at 0 0 270)
			(layer "F.SilkS")
			(hide yes)
			(effects
				(font
					(size 1.27 1.27)
				)
			)
		)
		(property "Value" "SC10U6D3V5KX-4GP"
			(at -0.0762 -6.1214 270)
			(unlocked yes)
			(layer "F.Fab")
			(hide yes)
			(effects
				(font
					(size 1.016 1.016)
					(thickness 0.1524)
				)
			)
		)
		(property "Device Type" "C805H58"
			(at -0.0762 -8.1534 270)
			(unlocked yes)
			(layer "F.Fab")
			(hide yes)
			(effects
				(font
					(size 1.016 1.016)
					(thickness 0.1524)
				)
			)
		)
		(duplicate_pad_numbers_are_jumpers no)
		(fp_line
			(start 0.6096 0)
			(end -0.6096 0)
			(stroke
				(width 0.3048)
				(type default)
			)
			(layer "F.SilkS")
		)
		(fp_poly
			(pts
				(xy -0.9017 1.4351) (xy 0.9017 1.4351) (xy 0.9017 -1.4351) (xy -0.9017 -1.4351)
			)
			(stroke
				(width 0)
				(type default)
			)
			(fill no)
			(layer "F.CrtYd")
		)
		(fp_poly
			(pts
				(xy 0.9017 1.4351) (xy 0.9017 -1.4351) (xy -0.9017 -1.4351) (xy -0.9017 1.4351)
			)
			(stroke
				(width 0)
				(type default)
			)
			(fill no)
			(layer "F.Fab")
		)
		(pad "1" smd rect
			(at 0 -0.8382 270)
			(size 1.5494 0.9398)
			(layers "F.Cu" "F.Mask" "F.Paste")
			(net "P1V8_STBY_LDO_IN2")
		)
		(pad "2" smd rect
			(at 0 0.8382 270)
			(size 1.5494 0.9398)
			(layers "F.Cu" "F.Mask" "F.Paste")
			(net "GND")
		)
	)
	(footprint ""
		(layer "F.Cu")
		(at 134.62 -18.796)
		(property "Reference" "R51"
			(at 0 0 0)
			(layer "F.SilkS")
			(hide yes)
			(effects
				(font
					(size 1.27 1.27)
				)
			)
		)
		(property "Value" "4K7R2F-GP"
			(at 0.064008 -3.993896 0)
			(unlocked yes)
			(layer "F.Fab")
			(hide yes)
			(effects
				(font
					(size 1.016 1.016)
					(thickness 0.1524)
				)
			)
		)
		(property "Device Type" "R402H16"
			(at 0.064008 -5.517896 0)
			(unlocked yes)
			(layer "F.Fab")
			(hide yes)
			(effects
				(font
					(size 1.016 1.016)
					(thickness 0.1524)
				)
			)
		)
		(duplicate_pad_numbers_are_jumpers no)
		(fp_rect
			(start -0.381 0.8382)
			(end 0.381 -0.8382)
			(stroke
				(width 0)
				(type default)
			)
			(fill no)
			(layer "F.CrtYd")
		)
		(fp_rect
			(start -0.381 0.8382)
			(end 0.381 -0.8382)
			(stroke
				(width 0)
				(type default)
			)
			(fill no)
			(layer "F.Fab")
		)
		(pad "1" smd custom
			(at 0 -0.4318)
			(size 0.127 0.127)
			(layers "F.Cu" "F.Mask" "F.Paste")
			(net "P3V3_STBY")
			(options
				(clearance outline)
				(anchor circle)
			)
			(primitives
				(gr_poly
					(pts
						(arc
							(start -0.2032 -0.2794)
							(mid -0.239121 -0.264521)
							(end -0.254 -0.2286)
						)
						(arc
							(start -0.254 0.2286)
							(mid -0.239121 0.264521)
							(end -0.2032 0.2794)
						)
						(arc
							(start 0.2032 0.2794)
							(mid 0.239121 0.264521)
							(end 0.254 0.2286)
						)
						(arc
							(start 0.254 -0.2286)
							(mid 0.239121 -0.264521)
							(end 0.2032 -0.2794)
						)
					)
					(width 0)
					(fill yes)
				)
			)
		)
		(pad "2" smd custom
			(at 0 0.4318)
			(size 0.127 0.127)
			(layers "F.Cu" "F.Mask" "F.Paste")
			(net "FPGA_PWRBTN#")
			(options
				(clearance outline)
				(anchor circle)
			)
			(primitives
				(gr_poly
					(pts
						(arc
							(start -0.2032 -0.2794)
							(mid -0.239121 -0.264521)
							(end -0.254 -0.2286)
						)
						(arc
							(start -0.254 0.2286)
							(mid -0.239121 0.264521)
							(end -0.2032 0.2794)
						)
						(arc
							(start 0.2032 0.2794)
							(mid 0.239121 0.264521)
							(end 0.254 0.2286)
						)
						(arc
							(start 0.254 -0.2286)
							(mid 0.239121 -0.264521)
							(end 0.2032 -0.2794)
						)
					)
					(width 0)
					(fill yes)
				)
			)
		)
	)
)
